# S9S_MB_2U (Grand Teton) — schematic netlist excerpt (pin names and nets, part order shuffled) for the footprints in the layout excerpt that follows; sources: Cadence DE-HDL packaged netlist, KiCad conversion of 03242023_DA0F0TMBIJ0_F0T_Motherboard_J_brd_V01_OCP.brd

C570  Q_CAP  0.1UF 25V 10% X7R  pkg 0402  page 236 : A = P3V3_AUX ; B = GND

PPQ9  MOSFET_NCH_1D3S  PSMNR58-30YLH EMPTY  pkg SOT1023  page 304
  \1\  = P12V_AUX
  \2\  = P12V_AUX
  \3\  = P12V_AUX
  \4\  = MB0_CM_GATE_G0
  \5\  = P12V_MAIN_R_0

(kicad_pcb
	(version 20260206)
	(generator "pcbnew")
	(generator_version "10.0")
	(general
		(thickness 1.6)
		(legacy_teardrops no)
	)
	(paper "A4")
	(title_block
		(title "03242023_DA0F0TMBIJ0_F0T_Motherboard_J_brd_V01_OCP.brd")
		(comment 1 "Grand Teton / footprints 2199-2200 of 6105")
	)
	(layers
		(0 "F.Cu" signal "TOP")
		(4 "In1.Cu" signal "GND")
		(6 "In2.Cu" signal "IN1")
		(8 "In3.Cu" signal "GND1")
		(10 "In4.Cu" signal "IN2")
		(12 "In5.Cu" signal "GND2")
		(14 "In6.Cu" signal "IN3")
		(16 "In7.Cu" signal "GND3")
		(18 "In8.Cu" signal "VCC")
		(20 "In9.Cu" signal "VCC1")
		(22 "In10.Cu" signal "GND4")
		(24 "In11.Cu" signal "IN4")
		(26 "In12.Cu" signal "GND5")
		(28 "In13.Cu" signal "IN5")
		(30 "In14.Cu" signal "GND6")
		(32 "In15.Cu" signal "IN6")
		(34 "In16.Cu" signal "GND7")
		(2 "B.Cu" signal "BOTTOM")
		(9 "F.Adhes" user "F.Adhesive")
		(11 "B.Adhes" user "B.Adhesive")
		(13 "F.Paste" user "Package Geometry/Pastemask Top")
		(15 "B.Paste" user "Package Geometry/Pastemask Bottom")
		(5 "F.SilkS" user "Ref Des/Silkscreen Top")
		(7 "B.SilkS" user "Ref Des/Silkscreen Bottom")
		(1 "F.Mask" user "Board Geometry/Soldermask Top")
		(3 "B.Mask" user "Board Geometry/Soldermask Bottom")
		(17 "Dwgs.User" user "User.Drawings")
		(19 "Cmts.User" user "User.Comments")
		(21 "Eco1.User" user "User.Eco1")
		(23 "Eco2.User" user "User.Eco2")
		(25 "Edge.Cuts" user "Board Geometry/Outline")
		(27 "Margin" user)
		(31 "F.CrtYd" user "Package Geometry/Place Bound Top")
		(29 "B.CrtYd" user "Package Geometry/Place Bound Bottom")
		(35 "F.Fab" user "Ref Des/Assembly Top")
		(33 "B.Fab" user "Ref Des/Assembly Bottom")
	)
	(footprint ""
		(layer "F.Cu")
		(at 277.9014 -398.78 90)
		(property "Reference" "PPQ9"
			(at -8.190992 -2.0828 0)
			(unlocked yes)
			(layer "F.SilkS")
			(effects
				(font
					(size 0.7874 0.5842)
					(thickness 0.1524)
				)
				(justify left)
			)
		)
		(property "Value" ""
			(at 0 0 90)
			(layer "F.Fab")
			(effects
				(font
					(size 1.27 1.27)
				)
			)
		)
		(duplicate_pad_numbers_are_jumpers no)
		(fp_line
			(start 2.350008 -2.649982)
			(end 2.350008 -2.4892)
			(stroke
				(width 0.1524)
				(type default)
			)
			(layer "F.SilkS")
		)
		(fp_line
			(start -2.350008 -2.649982)
			(end 2.350008 -2.649982)
			(stroke
				(width 0.1524)
				(type default)
			)
			(layer "F.SilkS")
		)
		(fp_line
			(start -2.350008 -2.4384)
			(end -2.350008 -2.649982)
			(stroke
				(width 0.1524)
				(type default)
			)
			(layer "F.SilkS")
		)
		(fp_line
			(start 2.350008 2.4892)
			(end 2.350008 2.649982)
			(stroke
				(width 0.1524)
				(type default)
			)
			(layer "F.SilkS")
		)
		(fp_line
			(start 2.350008 2.649982)
			(end -2.350008 2.649982)
			(stroke
				(width 0.1524)
				(type default)
			)
			(layer "F.SilkS")
		)
		(fp_line
			(start -2.350008 2.649982)
			(end -2.350008 2.413)
			(stroke
				(width 0.1524)
				(type default)
			)
			(layer "F.SilkS")
		)
		(fp_poly
			(pts
				(xy -3.717544 -1.905) (xy -4.758944 -2.3241) (xy -4.758944 -1.524)
			)
			(stroke
				(width 0)
				(type default)
			)
			(fill yes)
			(layer "F.SilkS")
		)
		(fp_line
			(start 2.350008 -2.649982)
			(end 2.350008 2.649982)
			(stroke
				(width 0.1)
				(type default)
			)
			(layer "F.Fab")
		)
		(fp_line
			(start -2.350008 -2.649982)
			(end 2.350008 -2.649982)
			(stroke
				(width 0.1)
				(type default)
			)
			(layer "F.Fab")
		)
		(fp_line
			(start 2.350008 2.649982)
			(end -2.350008 2.649982)
			(stroke
				(width 0.1)
				(type default)
			)
			(layer "F.Fab")
		)
		(fp_line
			(start -2.350008 2.649982)
			(end -2.350008 -2.649982)
			(stroke
				(width 0.1)
				(type default)
			)
			(layer "F.Fab")
		)
		(fp_poly
			(pts
				(xy -3.717544 -1.905) (xy -4.758944 -2.3241) (xy -4.758944 -1.524)
			)
			(stroke
				(width 0)
				(type default)
			)
			(fill yes)
			(layer "F.Fab")
		)
		(pad "1" smd rect
			(at -2.999994 -1.905)
			(size 0.7112 1.1684)
			(layers "F.Cu" "F.Mask" "F.Paste")
			(net "P12V_AUX")
		)
		(pad "2" smd rect
			(at -2.999994 -0.635)
			(size 0.7112 1.1684)
			(layers "F.Cu" "F.Mask" "F.Paste")
			(net "P12V_AUX")
		)
		(pad "3" smd rect
			(at -2.999994 0.635)
			(size 0.7112 1.1684)
			(layers "F.Cu" "F.Mask" "F.Paste")
			(net "P12V_AUX")
		)
		(pad "4" smd rect
			(at -2.999994 1.905)
			(size 0.7112 1.1684)
			(layers "F.Cu" "F.Mask" "F.Paste")
			(net "MB0_CM_GATE_G0")
		)
		(pad "5" smd circle
			(at 0.925068 0)
			(size 0 0)
			(layers "F.Cu" "F.Mask" "F.Paste")
			(net "P12V_MAIN_R_0")
		)
		(zone
			(layer "F.Cu")
			(hatch none 0.5)
			(connect_pads
				(clearance 0)
			)
			(min_thickness 0.25)
			(keepout
				(tracks not_allowed)
				(vias allowed)
				(pads allowed)
				(copperpour not_allowed)
				(footprints allowed)
			)
			(placement
				(enabled no)
				(sheetname "")
			)
			(fill
				(thermal_gap 0.5)
				(thermal_bridge_width 0.5)
				(island_removal_mode 0)
			)
			(polygon
				(pts
					(xy 275.7424 -397.3322) (xy 280.0604 -397.3322) (xy 280.543 -397.3322) (xy 280.543 -396.4305) (xy 275.2598 -396.4305)
					(xy 275.2598 -397.3322)
				)
			)
		)
	)
	(footprint ""
		(layer "F.Cu")
		(at 223.868488 -232.77957 90)
		(property "Reference" "C570"
			(at 0 0 90)
			(layer "F.SilkS")
			(hide yes)
			(effects
				(font
					(size 1.27 1.27)
				)
			)
		)
		(property "Value" ""
			(at 0 0 90)
			(layer "F.Fab")
			(effects
				(font
					(size 1.27 1.27)
				)
			)
		)
		(duplicate_pad_numbers_are_jumpers no)
		(fp_line
			(start 0.7874 -0.4064)
			(end 0.7874 0.4064)
			(stroke
				(width 0.1524)
				(type default)
			)
			(layer "F.SilkS")
		)
		(fp_line
			(start -0.7874 -0.4064)
			(end 0.7874 -0.4064)
			(stroke
				(width 0.1524)
				(type default)
			)
			(layer "F.SilkS")
		)
		(fp_line
			(start 0.7874 0.4064)
			(end -0.7874 0.4064)
			(stroke
				(width 0.1524)
				(type default)
			)
			(layer "F.SilkS")
		)
		(fp_line
			(start -0.7874 0.4064)
			(end -0.7874 -0.4064)
			(stroke
				(width 0.1524)
				(type default)
			)
			(layer "F.SilkS")
		)
		(fp_line
			(start -0.12065 -0.305054)
			(end -0.12065 -0.2794)
			(stroke
				(width 0.1)
				(type default)
			)
			(layer "F.Fab")
		)
		(fp_line
			(start -0.67945 -0.305054)
			(end -0.12065 -0.305054)
			(stroke
				(width 0.1)
				(type default)
			)
			(layer "F.Fab")
		)
		(fp_line
			(start 0.67945 -0.3048)
			(end 0.67945 0.3048)
			(stroke
				(width 0.1)
				(type default)
			)
			(layer "F.Fab")
		)
		(fp_line
			(start 0.12065 -0.3048)
			(end 0.67945 -0.3048)
			(stroke
				(width 0.1)
				(type default)
			)
			(layer "F.Fab")
		)
		(fp_line
			(start 0.12065 -0.2794)
			(end 0.12065 -0.3048)
			(stroke
				(width 0.1)
				(type default)
			)
			(layer "F.Fab")
		)
		(fp_line
			(start -0.12065 -0.2794)
			(end 0.12065 -0.2794)
			(stroke
				(width 0.1)
				(type default)
			)
			(layer "F.Fab")
		)
		(fp_line
			(start 0.120396 0.2794)
			(end -0.12065 0.2794)
			(stroke
				(width 0.1)
				(type default)
			)
			(layer "F.Fab")
		)
		(fp_line
			(start -0.12065 0.2794)
			(end -0.12065 0.3048)
			(stroke
				(width 0.1)
				(type default)
			)
			(layer "F.Fab")
		)
		(fp_line
			(start 0.67945 0.3048)
			(end 0.120396 0.3048)
			(stroke
				(width 0.1)
				(type default)
			)
			(layer "F.Fab")
		)
		(fp_line
			(start 0.120396 0.3048)
			(end 0.120396 0.2794)
			(stroke
				(width 0.1)
				(type default)
			)
			(layer "F.Fab")
		)
		(fp_line
			(start -0.12065 0.3048)
			(end -0.67945 0.3048)
			(stroke
				(width 0.1)
				(type default)
			)
			(layer "F.Fab")
		)
		(fp_line
			(start -0.67945 0.3048)
			(end -0.67945 -0.305054)
			(stroke
				(width 0.1)
				(type default)
			)
			(layer "F.Fab")
		)
		(pad "1" smd circle
			(at -0.40005 0 90)
			(size 0 0)
			(layers "F.Cu" "F.Mask" "F.Paste")
			(net "P3V3_AUX")
		)
		(pad "2" smd circle
			(at 0.40005 0 90)
			(size 0 0)
			(layers "F.Cu" "F.Mask" "F.Paste")
			(net "GND")
		)
	)
)
